(kicad_pcb
	(version 20260206)
	(generator "pcbnew")
	(generator_version "10.0")
	(general
		(thickness 1.6)
		(legacy_teardrops no)
	)
	(paper "A4")
	(title_block
		(title "01162023_DA0F0TEBIF0_F0T_Expander_BD_F_brd_V02_OCP.brd")
		(comment 1 "Grand Teton / footprints 8486-8492 of 9728")
	)
	(layers
		(0 "F.Cu" signal "TOP")
		(4 "In1.Cu" signal "GND")
		(6 "In2.Cu" signal "VCC")
		(8 "In3.Cu" signal "VCC1")
		(10 "In4.Cu" signal "GND1")
		(12 "In5.Cu" signal "IN1")
		(14 "In6.Cu" signal "GND2")
		(16 "In7.Cu" signal "IN2")
		(18 "In8.Cu" signal "GND3")
		(20 "In9.Cu" signal "IN3")
		(22 "In10.Cu" signal "GND4")
		(24 "In11.Cu" signal "IN4")
		(26 "In12.Cu" signal "GND5")
		(28 "In13.Cu" signal "IN5")
		(30 "In14.Cu" signal "GND6")
		(32 "In15.Cu" signal "IN6")
		(34 "In16.Cu" signal "GND7")
		(2 "B.Cu" signal "BOTTOM")
		(9 "F.Adhes" user "F.Adhesive")
		(11 "B.Adhes" user "B.Adhesive")
		(13 "F.Paste" user "Package Geometry/Pastemask Top")
		(15 "B.Paste" user "Package Geometry/Pastemask Bottom")
		(5 "F.SilkS" user "Ref Des/Silkscreen Top")
		(7 "B.SilkS" user "Ref Des/Silkscreen Bottom")
		(1 "F.Mask" user "Board Geometry/Soldermask Top")
		(3 "B.Mask" user "Board Geometry/Soldermask Bottom")
		(17 "Dwgs.User" user "User.Drawings")
		(19 "Cmts.User" user "User.Comments")
		(21 "Eco1.User" user "User.Eco1")
		(23 "Eco2.User" user "User.Eco2")
		(25 "Edge.Cuts" user "Board Geometry/Outline")
		(27 "Margin" user)
		(31 "F.CrtYd" user "Package Geometry/Place Bound Top")
		(29 "B.CrtYd" user "Package Geometry/Place Bound Bottom")
		(35 "F.Fab" user "Ref Des/Assembly Top")
		(33 "B.Fab" user "Ref Des/Assembly Bottom")
	)
	(footprint ""
		(layer "B.Cu")
		(at 14.830298 -229.997)
		(property "Reference" "R3448"
			(at 0 0 0)
			(layer "B.SilkS")
			(hide yes)
			(effects
				(font
					(size 1.27 1.27)
				)
				(justify mirror)
			)
		)
		(property "Value" ""
			(at 0 0 0)
			(layer "B.Fab")
			(effects
				(font
					(size 1.27 1.27)
				)
				(justify mirror)
			)
		)
		(duplicate_pad_numbers_are_jumpers no)
		(fp_line
			(start -0.7874 -0.4064)
			(end -0.7874 0.4064)
			(stroke
				(width 0.1524)
				(type default)
			)
			(layer "B.SilkS")
		)
		(fp_line
			(start -0.7874 0.4064)
			(end 0.7874 0.4064)
			(stroke
				(width 0.1524)
				(type default)
			)
			(layer "B.SilkS")
		)
		(fp_line
			(start 0.7874 -0.4064)
			(end -0.7874 -0.4064)
			(stroke
				(width 0.1524)
				(type default)
			)
			(layer "B.SilkS")
		)
		(fp_line
			(start 0.7874 0.4064)
			(end 0.7874 -0.4064)
			(stroke
				(width 0.1524)
				(type default)
			)
			(layer "B.SilkS")
		)
		(fp_line
			(start -0.67945 -0.3048)
			(end -0.67945 0.3048)
			(stroke
				(width 0.1)
				(type default)
			)
			(layer "B.Fab")
		)
		(fp_line
			(start -0.67945 0.3048)
			(end -0.120396 0.3048)
			(stroke
				(width 0.1)
				(type default)
			)
			(layer "B.Fab")
		)
		(fp_line
			(start -0.12065 -0.3048)
			(end -0.67945 -0.3048)
			(stroke
				(width 0.1)
				(type default)
			)
			(layer "B.Fab")
		)
		(fp_line
			(start -0.12065 -0.2794)
			(end -0.12065 -0.3048)
			(stroke
				(width 0.1)
				(type default)
			)
			(layer "B.Fab")
		)
		(fp_line
			(start -0.120396 0.2794)
			(end 0.12065 0.2794)
			(stroke
				(width 0.1)
				(type default)
			)
			(layer "B.Fab")
		)
		(fp_line
			(start -0.120396 0.3048)
			(end -0.120396 0.2794)
			(stroke
				(width 0.1)
				(type default)
			)
			(layer "B.Fab")
		)
		(fp_line
			(start 0.12065 -0.305054)
			(end 0.12065 -0.2794)
			(stroke
				(width 0.1)
				(type default)
			)
			(layer "B.Fab")
		)
		(fp_line
			(start 0.12065 -0.2794)
			(end -0.12065 -0.2794)
			(stroke
				(width 0.1)
				(type default)
			)
			(layer "B.Fab")
		)
		(fp_line
			(start 0.12065 0.2794)
			(end 0.12065 0.3048)
			(stroke
				(width 0.1)
				(type default)
			)
			(layer "B.Fab")
		)
		(fp_line
			(start 0.12065 0.3048)
			(end 0.67945 0.3048)
			(stroke
				(width 0.1)
				(type default)
			)
			(layer "B.Fab")
		)
		(fp_line
			(start 0.67945 -0.305054)
			(end 0.12065 -0.305054)
			(stroke
				(width 0.1)
				(type default)
			)
			(layer "B.Fab")
		)
		(fp_line
			(start 0.67945 0.3048)
			(end 0.67945 -0.305054)
			(stroke
				(width 0.1)
				(type default)
			)
			(layer "B.Fab")
		)
		(pad "1" smd circle
			(at 0.40005 0 180)
			(size 0 0)
			(layers "B.Cu" "B.Mask" "B.Paste")
			(net "SPI_PEX0_SDIO2_R")
		)
		(pad "2" smd circle
			(at -0.40005 0 180)
			(size 0 0)
			(layers "B.Cu" "B.Mask" "B.Paste")
			(net "SPI_PEX0_SDIO2_R1")
		)
	)
	(footprint ""
		(layer "B.Cu")
		(at 214.454486 -212.206586 180)
		(property "Reference" "R5533"
			(at 0 0 0)
			(layer "B.SilkS")
			(hide yes)
			(effects
				(font
					(size 1.27 1.27)
				)
				(justify mirror)
			)
		)
		(property "Value" ""
			(at 0 0 0)
			(layer "B.Fab")
			(effects
				(font
					(size 1.27 1.27)
				)
				(justify mirror)
			)
		)
		(duplicate_pad_numbers_are_jumpers no)
		(fp_line
			(start 0.7874 0.4064)
			(end 0.7874 -0.4064)
			(stroke
				(width 0.1524)
				(type default)
			)
			(layer "B.SilkS")
		)
		(fp_line
			(start 0.7874 -0.4064)
			(end -0.7874 -0.4064)
			(stroke
				(width 0.1524)
				(type default)
			)
			(layer "B.SilkS")
		)
		(fp_line
			(start -0.7874 0.4064)
			(end 0.7874 0.4064)
			(stroke
				(width 0.1524)
				(type default)
			)
			(layer "B.SilkS")
		)
		(fp_line
			(start -0.7874 -0.4064)
			(end -0.7874 0.4064)
			(stroke
				(width 0.1524)
				(type default)
			)
			(layer "B.SilkS")
		)
		(fp_line
			(start 0.67945 0.3048)
			(end 0.67945 -0.305054)
			(stroke
				(width 0.1)
				(type default)
			)
			(layer "B.Fab")
		)
		(fp_line
			(start 0.67945 -0.305054)
			(end 0.12065 -0.305054)
			(stroke
				(width 0.1)
				(type default)
			)
			(layer "B.Fab")
		)
		(fp_line
			(start 0.12065 0.3048)
			(end 0.67945 0.3048)
			(stroke
				(width 0.1)
				(type default)
			)
			(layer "B.Fab")
		)
		(fp_line
			(start 0.12065 0.2794)
			(end 0.12065 0.3048)
			(stroke
				(width 0.1)
				(type default)
			)
			(layer "B.Fab")
		)
		(fp_line
			(start 0.12065 -0.2794)
			(end -0.12065 -0.2794)
			(stroke
				(width 0.1)
				(type default)
			)
			(layer "B.Fab")
		)
		(fp_line
			(start 0.12065 -0.305054)
			(end 0.12065 -0.2794)
			(stroke
				(width 0.1)
				(type default)
			)
			(layer "B.Fab")
		)
		(fp_line
			(start -0.120396 0.3048)
			(end -0.120396 0.2794)
			(stroke
				(width 0.1)
				(type default)
			)
			(layer "B.Fab")
		)
		(fp_line
			(start -0.120396 0.2794)
			(end 0.12065 0.2794)
			(stroke
				(width 0.1)
				(type default)
			)
			(layer "B.Fab")
		)
		(fp_line
			(start -0.12065 -0.2794)
			(end -0.12065 -0.3048)
			(stroke
				(width 0.1)
				(type default)
			)
			(layer "B.Fab")
		)
		(fp_line
			(start -0.12065 -0.3048)
			(end -0.67945 -0.3048)
			(stroke
				(width 0.1)
				(type default)
			)
			(layer "B.Fab")
		)
		(fp_line
			(start -0.67945 0.3048)
			(end -0.120396 0.3048)
			(stroke
				(width 0.1)
				(type default)
			)
			(layer "B.Fab")
		)
		(fp_line
			(start -0.67945 -0.3048)
			(end -0.67945 0.3048)
			(stroke
				(width 0.1)
				(type default)
			)
			(layer "B.Fab")
		)
		(pad "1" smd circle
			(at 0.40005 0)
			(size 0 0)
			(layers "B.Cu" "B.Mask" "B.Paste")
			(net "GND")
		)
		(pad "2" smd circle
			(at -0.40005 0)
			(size 0 0)
			(layers "B.Cu" "B.Mask" "B.Paste")
			(net "UART_BIC_DEBUG_TX")
		)
	)
	(footprint ""
		(layer "B.Cu")
		(at 302.552354 -234.958636 90)
		(property "Reference" "R1866"
			(at 0 0 90)
			(layer "B.SilkS")
			(hide yes)
			(effects
				(font
					(size 1.27 1.27)
				)
				(justify mirror)
			)
		)
		(property "Value" ""
			(at 0 0 90)
			(layer "B.Fab")
			(effects
				(font
					(size 1.27 1.27)
				)
				(justify mirror)
			)
		)
		(duplicate_pad_numbers_are_jumpers no)
		(fp_line
			(start 0.7874 -0.4064)
			(end -0.7874 -0.4064)
			(stroke
				(width 0.1524)
				(type default)
			)
			(layer "B.SilkS")
		)
		(fp_line
			(start -0.7874 -0.4064)
			(end -0.7874 0.4064)
			(stroke
				(width 0.1524)
				(type default)
			)
			(layer "B.SilkS")
		)
		(fp_line
			(start 0.7874 0.4064)
			(end 0.7874 -0.4064)
			(stroke
				(width 0.1524)
				(type default)
			)
			(layer "B.SilkS")
		)
		(fp_line
			(start -0.7874 0.4064)
			(end 0.7874 0.4064)
			(stroke
				(width 0.1524)
				(type default)
			)
			(layer "B.SilkS")
		)
		(fp_line
			(start 0.67945 -0.305054)
			(end 0.12065 -0.305054)
			(stroke
				(width 0.1)
				(type default)
			)
			(layer "B.Fab")
		)
		(fp_line
			(start 0.12065 -0.305054)
			(end 0.12065 -0.2794)
			(stroke
				(width 0.1)
				(type default)
			)
			(layer "B.Fab")
		)
		(fp_line
			(start -0.12065 -0.3048)
			(end -0.67945 -0.3048)
			(stroke
				(width 0.1)
				(type default)
			)
			(layer "B.Fab")
		)
		(fp_line
			(start -0.67945 -0.3048)
			(end -0.67945 0.3048)
			(stroke
				(width 0.1)
				(type default)
			)
			(layer "B.Fab")
		)
		(fp_line
			(start 0.12065 -0.2794)
			(end -0.12065 -0.2794)
			(stroke
				(width 0.1)
				(type default)
			)
			(layer "B.Fab")
		)
		(fp_line
			(start -0.12065 -0.2794)
			(end -0.12065 -0.3048)
			(stroke
				(width 0.1)
				(type default)
			)
			(layer "B.Fab")
		)
		(fp_line
			(start 0.12065 0.2794)
			(end 0.12065 0.3048)
			(stroke
				(width 0.1)
				(type default)
			)
			(layer "B.Fab")
		)
		(fp_line
			(start -0.120396 0.2794)
			(end 0.12065 0.2794)
			(stroke
				(width 0.1)
				(type default)
			)
			(layer "B.Fab")
		)
		(fp_line
			(start 0.67945 0.3048)
			(end 0.67945 -0.305054)
			(stroke
				(width 0.1)
				(type default)
			)
			(layer "B.Fab")
		)
		(fp_line
			(start 0.12065 0.3048)
			(end 0.67945 0.3048)
			(stroke
				(width 0.1)
				(type default)
			)
			(layer "B.Fab")
		)
		(fp_line
			(start -0.120396 0.3048)
			(end -0.120396 0.2794)
			(stroke
				(width 0.1)
				(type default)
			)
			(layer "B.Fab")
		)
		(fp_line
			(start -0.67945 0.3048)
			(end -0.120396 0.3048)
			(stroke
				(width 0.1)
				(type default)
			)
			(layer "B.Fab")
		)
		(pad "1" smd circle
			(at 0.40005 0 270)
			(size 0 0)
			(layers "B.Cu" "B.Mask" "B.Paste")
			(net "RST_GPU_PERST_1_N")
		)
		(pad "2" smd circle
			(at -0.40005 0 270)
			(size 0 0)
			(layers "B.Cu" "B.Mask" "B.Paste")
			(net "RST_GPU_PERST_1_R_N")
		)
	)
	(footprint ""
		(layer "B.Cu")
		(at 100.439474 -335.69783 180)
		(property "Reference" "L16"
			(at 0 0 0)
			(layer "B.SilkS")
			(hide yes)
			(effects
				(font
					(size 1.27 1.27)
				)
				(justify mirror)
			)
		)
		(property "Value" ""
			(at 0 0 0)
			(layer "B.Fab")
			(effects
				(font
					(size 1.27 1.27)
				)
				(justify mirror)
			)
		)
		(duplicate_pad_numbers_are_jumpers no)
		(fp_line
			(start 1.63576 -0.8128)
			(end 1.63576 0.8128)
			(stroke
				(width 0.1524)
				(type default)
			)
			(layer "B.SilkS")
		)
		(fp_line
			(start 1.63576 -0.8128)
			(end -1.63576 -0.8128)
			(stroke
				(width 0.1524)
				(type default)
			)
			(layer "B.SilkS")
		)
		(fp_line
			(start -1.63576 0.8128)
			(end 1.63576 0.8128)
			(stroke
				(width 0.1524)
				(type default)
			)
			(layer "B.SilkS")
		)
		(fp_line
			(start -1.63576 -0.8128)
			(end -1.63576 0.8128)
			(stroke
				(width 0.1524)
				(type default)
			)
			(layer "B.SilkS")
		)
		(fp_line
			(start 1.56083 0.7366)
			(end 1.524 0.7366)
			(stroke
				(width 0.1)
				(type default)
			)
			(layer "B.Fab")
		)
		(fp_line
			(start 1.56083 -0.738632)
			(end 1.56083 0.7366)
			(stroke
				(width 0.1)
				(type default)
			)
			(layer "B.Fab")
		)
		(fp_line
			(start 1.524 0.7366)
			(end -1.524 0.7366)
			(stroke
				(width 0.1)
				(type default)
			)
			(layer "B.Fab")
		)
		(fp_line
			(start -1.524 0.7366)
			(end -1.560576 0.7366)
			(stroke
				(width 0.1)
				(type default)
			)
			(layer "B.Fab")
		)
		(fp_line
			(start -1.560576 0.7366)
			(end -1.560576 -0.738632)
			(stroke
				(width 0.1)
				(type default)
			)
			(layer "B.Fab")
		)
		(fp_line
			(start -1.560576 -0.738632)
			(end 1.56083 -0.738632)
			(stroke
				(width 0.1)
				(type default)
			)
			(layer "B.Fab")
		)
		(pad "1" smd rect
			(at 0.94996 0 180)
			(size 1.1176 1.3716)
			(layers "B.Cu" "B.Mask" "B.Paste")
			(net "P3V3")
		)
		(pad "2" smd rect
			(at -0.94996 0 180)
			(size 1.1176 1.3716)
			(layers "B.Cu" "B.Mask" "B.Paste")
			(net "P3V3_CLK_BUFFER_9ZXL0451E_VZX3P3")
		)
	)
	(footprint ""
		(layer "B.Cu")
		(at 402.724874 -293.99992 90)
		(property "Reference" "C1917"
			(at 0 0 90)
			(layer "B.SilkS")
			(hide yes)
			(effects
				(font
					(size 1.27 1.27)
				)
				(justify mirror)
			)
		)
		(property "Value" ""
			(at 0 0 90)
			(layer "B.Fab")
			(effects
				(font
					(size 1.27 1.27)
				)
				(justify mirror)
			)
		)
		(duplicate_pad_numbers_are_jumpers no)
		(fp_line
			(start 0.299974 -0.150114)
			(end -0.299974 -0.150114)
			(stroke
				(width 0.1)
				(type default)
			)
			(layer "B.Fab")
		)
		(fp_line
			(start -0.299974 -0.150114)
			(end -0.299974 0.150114)
			(stroke
				(width 0.1)
				(type default)
			)
			(layer "B.Fab")
		)
		(fp_line
			(start 0.299974 0.150114)
			(end 0.299974 -0.150114)
			(stroke
				(width 0.1)
				(type default)
			)
			(layer "B.Fab")
		)
		(fp_line
			(start -0.299974 0.150114)
			(end 0.299974 0.150114)
			(stroke
				(width 0.1)
				(type default)
			)
			(layer "B.Fab")
		)
		(pad "1" smd rect
			(at 0.2667 0 270)
			(size 0.3048 0.381)
			(layers "B.Cu" "B.Mask" "B.Paste")
			(net "P0V8_PEX3")
		)
		(pad "2" smd rect
			(at -0.2667 0 270)
			(size 0.3048 0.381)
			(layers "B.Cu" "B.Mask" "B.Paste")
			(net "GND")
		)
	)
	(footprint ""
		(layer "B.Cu")
		(at 349.422212 -319.633346 180)
		(property "Reference" "C1668"
			(at 0 0 0)
			(layer "B.SilkS")
			(hide yes)
			(effects
				(font
					(size 1.27 1.27)
				)
				(justify mirror)
			)
		)
		(property "Value" ""
			(at 0 0 0)
			(layer "B.Fab")
			(effects
				(font
					(size 1.27 1.27)
				)
				(justify mirror)
			)
		)
		(duplicate_pad_numbers_are_jumpers no)
		(fp_line
			(start 1.2954 0.5842)
			(end 1.2954 -0.5842)
			(stroke
				(width 0.1524)
				(type default)
			)
			(layer "B.SilkS")
		)
		(fp_line
			(start 1.2954 -0.5842)
			(end -1.2954 -0.5842)
			(stroke
				(width 0.1524)
				(type default)
			)
			(layer "B.SilkS")
		)
		(fp_line
			(start -1.2954 0.5842)
			(end 1.2954 0.5842)
			(stroke
				(width 0.1524)
				(type default)
			)
			(layer "B.SilkS")
		)
		(fp_line
			(start -1.2954 -0.5842)
			(end -1.2954 0.5842)
			(stroke
				(width 0.1524)
				(type default)
			)
			(layer "B.SilkS")
		)
		(fp_line
			(start 1.1938 0.4064)
			(end 1.1938 -0.4064)
			(stroke
				(width 0.1)
				(type default)
			)
			(layer "B.Fab")
		)
		(fp_line
			(start 1.1938 -0.4064)
			(end 0.8636 -0.4064)
			(stroke
				(width 0.1)
				(type default)
			)
			(layer "B.Fab")
		)
		(fp_line
			(start 0.8636 0.4572)
			(end 0.8636 0.4064)
			(stroke
				(width 0.1)
				(type default)
			)
			(layer "B.Fab")
		)
		(fp_line
			(start 0.8636 0.4064)
			(end 1.1938 0.4064)
			(stroke
				(width 0.1)
				(type default)
			)
			(layer "B.Fab")
		)
		(fp_line
			(start 0.8636 -0.4064)
			(end 0.8636 -0.4572)
			(stroke
				(width 0.1)
				(type default)
			)
			(layer "B.Fab")
		)
		(fp_line
			(start 0.8636 -0.4572)
			(end -0.8636 -0.4572)
			(stroke
				(width 0.1)
				(type default)
			)
			(layer "B.Fab")
		)
		(fp_line
			(start -0.8636 0.4572)
			(end 0.8636 0.4572)
			(stroke
				(width 0.1)
				(type default)
			)
			(layer "B.Fab")
		)
		(fp_line
			(start -0.8636 0.4064)
			(end -0.8636 0.4572)
			(stroke
				(width 0.1)
				(type default)
			)
			(layer "B.Fab")
		)
		(fp_line
			(start -0.8636 -0.4064)
			(end -1.1938 -0.4064)
			(stroke
				(width 0.1)
				(type default)
			)
			(layer "B.Fab")
		)
		(fp_line
			(start -0.8636 -0.4572)
			(end -0.8636 -0.4064)
			(stroke
				(width 0.1)
				(type default)
			)
			(layer "B.Fab")
		)
		(fp_line
			(start -1.1938 0.4064)
			(end -0.8636 0.4064)
			(stroke
				(width 0.1)
				(type default)
			)
			(layer "B.Fab")
		)
		(fp_line
			(start -1.1938 -0.4064)
			(end -1.1938 0.4064)
			(stroke
				(width 0.1)
				(type default)
			)
			(layer "B.Fab")
		)
		(pad "1" smd rect
			(at 0.7366 0 90)
			(size 0.7112 0.8128)
			(layers "B.Cu" "B.Mask" "B.Paste")
			(net "P0V8_SERDES_VDDA_PEX2")
		)
		(pad "2" smd rect
			(at -0.7366 0 90)
			(size 0.7112 0.8128)
			(layers "B.Cu" "B.Mask" "B.Paste")
			(net "GND")
		)
	)
	(footprint ""
		(layer "B.Cu")
		(at 47.77486 -290.941506 90)
		(property "Reference" "C3059"
			(at 0 0 90)
			(layer "B.SilkS")
			(hide yes)
			(effects
				(font
					(size 1.27 1.27)
				)
				(justify mirror)
			)
		)
		(property "Value" ""
			(at 0 0 90)
			(layer "B.Fab")
			(effects
				(font
					(size 1.27 1.27)
				)
				(justify mirror)
			)
		)
		(duplicate_pad_numbers_are_jumpers no)
		(fp_line
			(start 0.299974 -0.150114)
			(end -0.299974 -0.150114)
			(stroke
				(width 0.1)
				(type default)
			)
			(layer "B.Fab")
		)
		(fp_line
			(start -0.299974 -0.150114)
			(end -0.299974 0.150114)
			(stroke
				(width 0.1)
				(type default)
			)
			(layer "B.Fab")
		)
		(fp_line
			(start 0.299974 0.150114)
			(end 0.299974 -0.150114)
			(stroke
				(width 0.1)
				(type default)
			)
			(layer "B.Fab")
		)
		(fp_line
			(start -0.299974 0.150114)
			(end 0.299974 0.150114)
			(stroke
				(width 0.1)
				(type default)
			)
			(layer "B.Fab")
		)
		(pad "1" smd rect
			(at 0.2667 0 270)
			(size 0.3048 0.381)
			(layers "B.Cu" "B.Mask" "B.Paste")
			(net "PCEPLL7_VDDA18_PEX0")
		)
		(pad "2" smd rect
			(at -0.2667 0 270)
			(size 0.3048 0.381)
			(layers "B.Cu" "B.Mask" "B.Paste")
			(net "GND")
		)
	)
)
